(kicad_pcb
	(version 20260206)
	(generator "pcbnew")
	(generator_version "10.0")
	(general
		(thickness 1.6)
		(legacy_teardrops no)
	)
	(paper "A4")
	(title_block
		(title "01162023_DA0F0TEBIF0_F0T_Expander_BD_F_brd_V02_OCP.brd")
		(comment 1 "Grand Teton / footprints 9615-9623 of 9728")
	)
	(layers
		(0 "F.Cu" signal "TOP")
		(4 "In1.Cu" signal "GND")
		(6 "In2.Cu" signal "VCC")
		(8 "In3.Cu" signal "VCC1")
		(10 "In4.Cu" signal "GND1")
		(12 "In5.Cu" signal "IN1")
		(14 "In6.Cu" signal "GND2")
		(16 "In7.Cu" signal "IN2")
		(18 "In8.Cu" signal "GND3")
		(20 "In9.Cu" signal "IN3")
		(22 "In10.Cu" signal "GND4")
		(24 "In11.Cu" signal "IN4")
		(26 "In12.Cu" signal "GND5")
		(28 "In13.Cu" signal "IN5")
		(30 "In14.Cu" signal "GND6")
		(32 "In15.Cu" signal "IN6")
		(34 "In16.Cu" signal "GND7")
		(2 "B.Cu" signal "BOTTOM")
		(9 "F.Adhes" user "F.Adhesive")
		(11 "B.Adhes" user "B.Adhesive")
		(13 "F.Paste" user "Package Geometry/Pastemask Top")
		(15 "B.Paste" user "Package Geometry/Pastemask Bottom")
		(5 "F.SilkS" user "Ref Des/Silkscreen Top")
		(7 "B.SilkS" user "Ref Des/Silkscreen Bottom")
		(1 "F.Mask" user "Board Geometry/Soldermask Top")
		(3 "B.Mask" user "Board Geometry/Soldermask Bottom")
		(17 "Dwgs.User" user "User.Drawings")
		(19 "Cmts.User" user "User.Comments")
		(21 "Eco1.User" user "User.Eco1")
		(23 "Eco2.User" user "User.Eco2")
		(25 "Edge.Cuts" user "Board Geometry/Outline")
		(27 "Margin" user)
		(31 "F.CrtYd" user "Package Geometry/Place Bound Top")
		(29 "B.CrtYd" user "Package Geometry/Place Bound Bottom")
		(35 "F.Fab" user "Ref Des/Assembly Top")
		(33 "B.Fab" user "Ref Des/Assembly Bottom")
	)
	(footprint ""
		(layer "B.Cu")
		(at 226.546664 -207.02016 -90)
		(property "Reference" "R5284"
			(at 0 0 90)
			(layer "B.SilkS")
			(hide yes)
			(effects
				(font
					(size 1.27 1.27)
				)
				(justify mirror)
			)
		)
		(property "Value" ""
			(at 0 0 90)
			(layer "B.Fab")
			(effects
				(font
					(size 1.27 1.27)
				)
				(justify mirror)
			)
		)
		(duplicate_pad_numbers_are_jumpers no)
		(fp_line
			(start -0.7874 0.4064)
			(end 0.7874 0.4064)
			(stroke
				(width 0.1524)
				(type default)
			)
			(layer "B.SilkS")
		)
		(fp_line
			(start 0.7874 0.4064)
			(end 0.7874 -0.4064)
			(stroke
				(width 0.1524)
				(type default)
			)
			(layer "B.SilkS")
		)
		(fp_line
			(start -0.7874 -0.4064)
			(end -0.7874 0.4064)
			(stroke
				(width 0.1524)
				(type default)
			)
			(layer "B.SilkS")
		)
		(fp_line
			(start 0.7874 -0.4064)
			(end -0.7874 -0.4064)
			(stroke
				(width 0.1524)
				(type default)
			)
			(layer "B.SilkS")
		)
		(fp_line
			(start -0.67945 0.3048)
			(end -0.120396 0.3048)
			(stroke
				(width 0.1)
				(type default)
			)
			(layer "B.Fab")
		)
		(fp_line
			(start -0.120396 0.3048)
			(end -0.120396 0.2794)
			(stroke
				(width 0.1)
				(type default)
			)
			(layer "B.Fab")
		)
		(fp_line
			(start 0.12065 0.3048)
			(end 0.67945 0.3048)
			(stroke
				(width 0.1)
				(type default)
			)
			(layer "B.Fab")
		)
		(fp_line
			(start 0.67945 0.3048)
			(end 0.67945 -0.305054)
			(stroke
				(width 0.1)
				(type default)
			)
			(layer "B.Fab")
		)
		(fp_line
			(start -0.120396 0.2794)
			(end 0.12065 0.2794)
			(stroke
				(width 0.1)
				(type default)
			)
			(layer "B.Fab")
		)
		(fp_line
			(start 0.12065 0.2794)
			(end 0.12065 0.3048)
			(stroke
				(width 0.1)
				(type default)
			)
			(layer "B.Fab")
		)
		(fp_line
			(start -0.12065 -0.2794)
			(end -0.12065 -0.3048)
			(stroke
				(width 0.1)
				(type default)
			)
			(layer "B.Fab")
		)
		(fp_line
			(start 0.12065 -0.2794)
			(end -0.12065 -0.2794)
			(stroke
				(width 0.1)
				(type default)
			)
			(layer "B.Fab")
		)
		(fp_line
			(start -0.67945 -0.3048)
			(end -0.67945 0.3048)
			(stroke
				(width 0.1)
				(type default)
			)
			(layer "B.Fab")
		)
		(fp_line
			(start -0.12065 -0.3048)
			(end -0.67945 -0.3048)
			(stroke
				(width 0.1)
				(type default)
			)
			(layer "B.Fab")
		)
		(fp_line
			(start 0.12065 -0.305054)
			(end 0.12065 -0.2794)
			(stroke
				(width 0.1)
				(type default)
			)
			(layer "B.Fab")
		)
		(fp_line
			(start 0.67945 -0.305054)
			(end 0.12065 -0.305054)
			(stroke
				(width 0.1)
				(type default)
			)
			(layer "B.Fab")
		)
		(pad "1" smd circle
			(at 0.40005 0 90)
			(size 0 0)
			(layers "B.Cu" "B.Mask" "B.Paste")
			(net "GND")
		)
		(pad "2" smd circle
			(at -0.40005 0 90)
			(size 0 0)
			(layers "B.Cu" "B.Mask" "B.Paste")
			(net "JTAG_BIC_TMS_R")
		)
	)
	(footprint ""
		(layer "B.Cu")
		(at 297.074844 -297.79976 -90)
		(property "Reference" "C1652"
			(at 0 0 90)
			(layer "B.SilkS")
			(hide yes)
			(effects
				(font
					(size 1.27 1.27)
				)
				(justify mirror)
			)
		)
		(property "Value" ""
			(at 0 0 90)
			(layer "B.Fab")
			(effects
				(font
					(size 1.27 1.27)
				)
				(justify mirror)
			)
		)
		(duplicate_pad_numbers_are_jumpers no)
		(fp_line
			(start -0.299974 0.150114)
			(end 0.299974 0.150114)
			(stroke
				(width 0.1)
				(type default)
			)
			(layer "B.Fab")
		)
		(fp_line
			(start 0.299974 0.150114)
			(end 0.299974 -0.150114)
			(stroke
				(width 0.1)
				(type default)
			)
			(layer "B.Fab")
		)
		(fp_line
			(start -0.299974 -0.150114)
			(end -0.299974 0.150114)
			(stroke
				(width 0.1)
				(type default)
			)
			(layer "B.Fab")
		)
		(fp_line
			(start 0.299974 -0.150114)
			(end -0.299974 -0.150114)
			(stroke
				(width 0.1)
				(type default)
			)
			(layer "B.Fab")
		)
		(pad "1" smd rect
			(at 0.2667 0 90)
			(size 0.3048 0.381)
			(layers "B.Cu" "B.Mask" "B.Paste")
			(net "P0V8_PEX2")
		)
		(pad "2" smd rect
			(at -0.2667 0 90)
			(size 0.3048 0.381)
			(layers "B.Cu" "B.Mask" "B.Paste")
			(net "GND")
		)
	)
	(footprint ""
		(layer "B.Cu")
		(at 297.549824 -288.299906 90)
		(property "Reference" "C3273"
			(at 0 0 90)
			(layer "B.SilkS")
			(hide yes)
			(effects
				(font
					(size 1.27 1.27)
				)
				(justify mirror)
			)
		)
		(property "Value" ""
			(at 0 0 90)
			(layer "B.Fab")
			(effects
				(font
					(size 1.27 1.27)
				)
				(justify mirror)
			)
		)
		(duplicate_pad_numbers_are_jumpers no)
		(fp_line
			(start 0.299974 -0.150114)
			(end -0.299974 -0.150114)
			(stroke
				(width 0.1)
				(type default)
			)
			(layer "B.Fab")
		)
		(fp_line
			(start -0.299974 -0.150114)
			(end -0.299974 0.150114)
			(stroke
				(width 0.1)
				(type default)
			)
			(layer "B.Fab")
		)
		(fp_line
			(start 0.299974 0.150114)
			(end 0.299974 -0.150114)
			(stroke
				(width 0.1)
				(type default)
			)
			(layer "B.Fab")
		)
		(fp_line
			(start -0.299974 0.150114)
			(end 0.299974 0.150114)
			(stroke
				(width 0.1)
				(type default)
			)
			(layer "B.Fab")
		)
		(pad "1" smd rect
			(at 0.2667 0 270)
			(size 0.3048 0.381)
			(layers "B.Cu" "B.Mask" "B.Paste")
			(net "P1V25_PEX2")
		)
		(pad "2" smd rect
			(at -0.2667 0 270)
			(size 0.3048 0.381)
			(layers "B.Cu" "B.Mask" "B.Paste")
			(net "GND")
		)
	)
	(footprint ""
		(layer "B.Cu")
		(at 40.649906 -288.774886 -90)
		(property "Reference" "R3292"
			(at 0 0 90)
			(layer "B.SilkS")
			(hide yes)
			(effects
				(font
					(size 1.27 1.27)
				)
				(justify mirror)
			)
		)
		(property "Value" ""
			(at 0 0 90)
			(layer "B.Fab")
			(effects
				(font
					(size 1.27 1.27)
				)
				(justify mirror)
			)
		)
		(duplicate_pad_numbers_are_jumpers no)
		(fp_line
			(start -0.7874 0.4064)
			(end 0.7874 0.4064)
			(stroke
				(width 0.1524)
				(type default)
			)
			(layer "B.SilkS")
		)
		(fp_line
			(start 0.7874 0.4064)
			(end 0.7874 -0.4064)
			(stroke
				(width 0.1524)
				(type default)
			)
			(layer "B.SilkS")
		)
		(fp_line
			(start -0.7874 -0.4064)
			(end -0.7874 0.4064)
			(stroke
				(width 0.1524)
				(type default)
			)
			(layer "B.SilkS")
		)
		(fp_line
			(start 0.7874 -0.4064)
			(end -0.7874 -0.4064)
			(stroke
				(width 0.1524)
				(type default)
			)
			(layer "B.SilkS")
		)
		(fp_line
			(start -0.67945 0.3048)
			(end -0.120396 0.3048)
			(stroke
				(width 0.1)
				(type default)
			)
			(layer "B.Fab")
		)
		(fp_line
			(start -0.120396 0.3048)
			(end -0.120396 0.2794)
			(stroke
				(width 0.1)
				(type default)
			)
			(layer "B.Fab")
		)
		(fp_line
			(start 0.12065 0.3048)
			(end 0.67945 0.3048)
			(stroke
				(width 0.1)
				(type default)
			)
			(layer "B.Fab")
		)
		(fp_line
			(start 0.67945 0.3048)
			(end 0.67945 -0.305054)
			(stroke
				(width 0.1)
				(type default)
			)
			(layer "B.Fab")
		)
		(fp_line
			(start -0.120396 0.2794)
			(end 0.12065 0.2794)
			(stroke
				(width 0.1)
				(type default)
			)
			(layer "B.Fab")
		)
		(fp_line
			(start 0.12065 0.2794)
			(end 0.12065 0.3048)
			(stroke
				(width 0.1)
				(type default)
			)
			(layer "B.Fab")
		)
		(fp_line
			(start -0.12065 -0.2794)
			(end -0.12065 -0.3048)
			(stroke
				(width 0.1)
				(type default)
			)
			(layer "B.Fab")
		)
		(fp_line
			(start 0.12065 -0.2794)
			(end -0.12065 -0.2794)
			(stroke
				(width 0.1)
				(type default)
			)
			(layer "B.Fab")
		)
		(fp_line
			(start -0.67945 -0.3048)
			(end -0.67945 0.3048)
			(stroke
				(width 0.1)
				(type default)
			)
			(layer "B.Fab")
		)
		(fp_line
			(start -0.12065 -0.3048)
			(end -0.67945 -0.3048)
			(stroke
				(width 0.1)
				(type default)
			)
			(layer "B.Fab")
		)
		(fp_line
			(start 0.12065 -0.305054)
			(end 0.12065 -0.2794)
			(stroke
				(width 0.1)
				(type default)
			)
			(layer "B.Fab")
		)
		(fp_line
			(start 0.67945 -0.305054)
			(end 0.12065 -0.305054)
			(stroke
				(width 0.1)
				(type default)
			)
			(layer "B.Fab")
		)
		(pad "1" smd circle
			(at 0.40005 0 90)
			(size 0 0)
			(layers "B.Cu" "B.Mask" "B.Paste")
			(net "SPI_PEX0_CS_R_N")
		)
		(pad "2" smd circle
			(at -0.40005 0 90)
			(size 0 0)
			(layers "B.Cu" "B.Mask" "B.Paste")
			(net "SPI_PEX0_CS_N")
		)
	)
	(footprint ""
		(layer "B.Cu")
		(at 287.099756 -288.299906 90)
		(property "Reference" "C3278"
			(at 0 0 90)
			(layer "B.SilkS")
			(hide yes)
			(effects
				(font
					(size 1.27 1.27)
				)
				(justify mirror)
			)
		)
		(property "Value" ""
			(at 0 0 90)
			(layer "B.Fab")
			(effects
				(font
					(size 1.27 1.27)
				)
				(justify mirror)
			)
		)
		(duplicate_pad_numbers_are_jumpers no)
		(fp_line
			(start 0.299974 -0.150114)
			(end -0.299974 -0.150114)
			(stroke
				(width 0.1)
				(type default)
			)
			(layer "B.Fab")
		)
		(fp_line
			(start -0.299974 -0.150114)
			(end -0.299974 0.150114)
			(stroke
				(width 0.1)
				(type default)
			)
			(layer "B.Fab")
		)
		(fp_line
			(start 0.299974 0.150114)
			(end 0.299974 -0.150114)
			(stroke
				(width 0.1)
				(type default)
			)
			(layer "B.Fab")
		)
		(fp_line
			(start -0.299974 0.150114)
			(end 0.299974 0.150114)
			(stroke
				(width 0.1)
				(type default)
			)
			(layer "B.Fab")
		)
		(pad "1" smd rect
			(at 0.2667 0 270)
			(size 0.3048 0.381)
			(layers "B.Cu" "B.Mask" "B.Paste")
			(net "P1V25_PEX2")
		)
		(pad "2" smd rect
			(at -0.2667 0 270)
			(size 0.3048 0.381)
			(layers "B.Cu" "B.Mask" "B.Paste")
			(net "GND")
		)
	)
	(footprint ""
		(layer "B.Cu")
		(at 237.562644 -231.225598 -90)
		(property "Reference" "R4527"
			(at 0 0 90)
			(layer "B.SilkS")
			(hide yes)
			(effects
				(font
					(size 1.27 1.27)
				)
				(justify mirror)
			)
		)
		(property "Value" ""
			(at 0 0 90)
			(layer "B.Fab")
			(effects
				(font
					(size 1.27 1.27)
				)
				(justify mirror)
			)
		)
		(duplicate_pad_numbers_are_jumpers no)
		(fp_line
			(start -0.7874 0.4064)
			(end 0.7874 0.4064)
			(stroke
				(width 0.1524)
				(type default)
			)
			(layer "B.SilkS")
		)
		(fp_line
			(start 0.7874 0.4064)
			(end 0.7874 -0.4064)
			(stroke
				(width 0.1524)
				(type default)
			)
			(layer "B.SilkS")
		)
		(fp_line
			(start -0.7874 -0.4064)
			(end -0.7874 0.4064)
			(stroke
				(width 0.1524)
				(type default)
			)
			(layer "B.SilkS")
		)
		(fp_line
			(start 0.7874 -0.4064)
			(end -0.7874 -0.4064)
			(stroke
				(width 0.1524)
				(type default)
			)
			(layer "B.SilkS")
		)
		(fp_line
			(start -0.67945 0.3048)
			(end -0.120396 0.3048)
			(stroke
				(width 0.1)
				(type default)
			)
			(layer "B.Fab")
		)
		(fp_line
			(start -0.120396 0.3048)
			(end -0.120396 0.2794)
			(stroke
				(width 0.1)
				(type default)
			)
			(layer "B.Fab")
		)
		(fp_line
			(start 0.12065 0.3048)
			(end 0.67945 0.3048)
			(stroke
				(width 0.1)
				(type default)
			)
			(layer "B.Fab")
		)
		(fp_line
			(start 0.67945 0.3048)
			(end 0.67945 -0.305054)
			(stroke
				(width 0.1)
				(type default)
			)
			(layer "B.Fab")
		)
		(fp_line
			(start -0.120396 0.2794)
			(end 0.12065 0.2794)
			(stroke
				(width 0.1)
				(type default)
			)
			(layer "B.Fab")
		)
		(fp_line
			(start 0.12065 0.2794)
			(end 0.12065 0.3048)
			(stroke
				(width 0.1)
				(type default)
			)
			(layer "B.Fab")
		)
		(fp_line
			(start -0.12065 -0.2794)
			(end -0.12065 -0.3048)
			(stroke
				(width 0.1)
				(type default)
			)
			(layer "B.Fab")
		)
		(fp_line
			(start 0.12065 -0.2794)
			(end -0.12065 -0.2794)
			(stroke
				(width 0.1)
				(type default)
			)
			(layer "B.Fab")
		)
		(fp_line
			(start -0.67945 -0.3048)
			(end -0.67945 0.3048)
			(stroke
				(width 0.1)
				(type default)
			)
			(layer "B.Fab")
		)
		(fp_line
			(start -0.12065 -0.3048)
			(end -0.67945 -0.3048)
			(stroke
				(width 0.1)
				(type default)
			)
			(layer "B.Fab")
		)
		(fp_line
			(start 0.12065 -0.305054)
			(end 0.12065 -0.2794)
			(stroke
				(width 0.1)
				(type default)
			)
			(layer "B.Fab")
		)
		(fp_line
			(start 0.67945 -0.305054)
			(end 0.12065 -0.305054)
			(stroke
				(width 0.1)
				(type default)
			)
			(layer "B.Fab")
		)
		(pad "1" smd circle
			(at 0.40005 0 90)
			(size 0 0)
			(layers "B.Cu" "B.Mask" "B.Paste")
			(net "SSD13_PWRDIS_BIC")
		)
		(pad "2" smd circle
			(at -0.40005 0 90)
			(size 0 0)
			(layers "B.Cu" "B.Mask" "B.Paste")
			(net "SSD13_PWRDIS_BIC_R")
		)
	)
	(footprint ""
		(layer "B.Cu")
		(at 108.146342 -321.810888 -90)
		(property "Reference" "R6458"
			(at 0 0 90)
			(layer "B.SilkS")
			(hide yes)
			(effects
				(font
					(size 1.27 1.27)
				)
				(justify mirror)
			)
		)
		(property "Value" ""
			(at 0 0 90)
			(layer "B.Fab")
			(effects
				(font
					(size 1.27 1.27)
				)
				(justify mirror)
			)
		)
		(duplicate_pad_numbers_are_jumpers no)
		(fp_line
			(start -0.7874 0.4064)
			(end 0.7874 0.4064)
			(stroke
				(width 0.1524)
				(type default)
			)
			(layer "B.SilkS")
		)
		(fp_line
			(start 0.7874 0.4064)
			(end 0.7874 -0.4064)
			(stroke
				(width 0.1524)
				(type default)
			)
			(layer "B.SilkS")
		)
		(fp_line
			(start -0.7874 -0.4064)
			(end -0.7874 0.4064)
			(stroke
				(width 0.1524)
				(type default)
			)
			(layer "B.SilkS")
		)
		(fp_line
			(start 0.7874 -0.4064)
			(end -0.7874 -0.4064)
			(stroke
				(width 0.1524)
				(type default)
			)
			(layer "B.SilkS")
		)
		(fp_line
			(start -0.67945 0.3048)
			(end -0.120396 0.3048)
			(stroke
				(width 0.1)
				(type default)
			)
			(layer "B.Fab")
		)
		(fp_line
			(start -0.120396 0.3048)
			(end -0.120396 0.2794)
			(stroke
				(width 0.1)
				(type default)
			)
			(layer "B.Fab")
		)
		(fp_line
			(start 0.12065 0.3048)
			(end 0.67945 0.3048)
			(stroke
				(width 0.1)
				(type default)
			)
			(layer "B.Fab")
		)
		(fp_line
			(start 0.67945 0.3048)
			(end 0.67945 -0.305054)
			(stroke
				(width 0.1)
				(type default)
			)
			(layer "B.Fab")
		)
		(fp_line
			(start -0.120396 0.2794)
			(end 0.12065 0.2794)
			(stroke
				(width 0.1)
				(type default)
			)
			(layer "B.Fab")
		)
		(fp_line
			(start 0.12065 0.2794)
			(end 0.12065 0.3048)
			(stroke
				(width 0.1)
				(type default)
			)
			(layer "B.Fab")
		)
		(fp_line
			(start -0.12065 -0.2794)
			(end -0.12065 -0.3048)
			(stroke
				(width 0.1)
				(type default)
			)
			(layer "B.Fab")
		)
		(fp_line
			(start 0.12065 -0.2794)
			(end -0.12065 -0.2794)
			(stroke
				(width 0.1)
				(type default)
			)
			(layer "B.Fab")
		)
		(fp_line
			(start -0.67945 -0.3048)
			(end -0.67945 0.3048)
			(stroke
				(width 0.1)
				(type default)
			)
			(layer "B.Fab")
		)
		(fp_line
			(start -0.12065 -0.3048)
			(end -0.67945 -0.3048)
			(stroke
				(width 0.1)
				(type default)
			)
			(layer "B.Fab")
		)
		(fp_line
			(start 0.12065 -0.305054)
			(end 0.12065 -0.2794)
			(stroke
				(width 0.1)
				(type default)
			)
			(layer "B.Fab")
		)
		(fp_line
			(start 0.67945 -0.305054)
			(end 0.12065 -0.305054)
			(stroke
				(width 0.1)
				(type default)
			)
			(layer "B.Fab")
		)
		(pad "1" smd circle
			(at 0.40005 0 90)
			(size 0 0)
			(layers "B.Cu" "B.Mask" "B.Paste")
			(net "P0V8_SERDES_VDDA_PEX0")
		)
		(pad "2" smd circle
			(at -0.40005 0 90)
			(size 0 0)
			(layers "B.Cu" "B.Mask" "B.Paste")
			(net "P0V8_SERDES_VDDA_PEX0_C9")
		)
	)
	(footprint ""
		(layer "B.Cu")
		(at 173.375066 -293.99992 -90)
		(property "Reference" "C1402"
			(at 0 0 90)
			(layer "B.SilkS")
			(hide yes)
			(effects
				(font
					(size 1.27 1.27)
				)
				(justify mirror)
			)
		)
		(property "Value" ""
			(at 0 0 90)
			(layer "B.Fab")
			(effects
				(font
					(size 1.27 1.27)
				)
				(justify mirror)
			)
		)
		(duplicate_pad_numbers_are_jumpers no)
		(fp_line
			(start -0.299974 0.150114)
			(end 0.299974 0.150114)
			(stroke
				(width 0.1)
				(type default)
			)
			(layer "B.Fab")
		)
		(fp_line
			(start 0.299974 0.150114)
			(end 0.299974 -0.150114)
			(stroke
				(width 0.1)
				(type default)
			)
			(layer "B.Fab")
		)
		(fp_line
			(start -0.299974 -0.150114)
			(end -0.299974 0.150114)
			(stroke
				(width 0.1)
				(type default)
			)
			(layer "B.Fab")
		)
		(fp_line
			(start 0.299974 -0.150114)
			(end -0.299974 -0.150114)
			(stroke
				(width 0.1)
				(type default)
			)
			(layer "B.Fab")
		)
		(pad "1" smd rect
			(at 0.2667 0 90)
			(size 0.3048 0.381)
			(layers "B.Cu" "B.Mask" "B.Paste")
			(net "P0V8_PEX1")
		)
		(pad "2" smd rect
			(at -0.2667 0 90)
			(size 0.3048 0.381)
			(layers "B.Cu" "B.Mask" "B.Paste")
			(net "GND")
		)
	)
	(footprint ""
		(layer "B.Cu")
		(at 397.49984 -288.774886 180)
		(property "Reference" "C3532"
			(at 0 0 0)
			(layer "B.SilkS")
			(hide yes)
			(effects
				(font
					(size 1.27 1.27)
				)
				(justify mirror)
			)
		)
		(property "Value" ""
			(at 0 0 0)
			(layer "B.Fab")
			(effects
				(font
					(size 1.27 1.27)
				)
				(justify mirror)
			)
		)
		(duplicate_pad_numbers_are_jumpers no)
		(fp_line
			(start 0.299974 0.150114)
			(end 0.299974 -0.150114)
			(stroke
				(width 0.1)
				(type default)
			)
			(layer "B.Fab")
		)
		(fp_line
			(start 0.299974 -0.150114)
			(end -0.299974 -0.150114)
			(stroke
				(width 0.1)
				(type default)
			)
			(layer "B.Fab")
		)
		(fp_line
			(start -0.299974 0.150114)
			(end 0.299974 0.150114)
			(stroke
				(width 0.1)
				(type default)
			)
			(layer "B.Fab")
		)
		(fp_line
			(start -0.299974 -0.150114)
			(end -0.299974 0.150114)
			(stroke
				(width 0.1)
				(type default)
			)
			(layer "B.Fab")
		)
		(pad "1" smd rect
			(at 0.2667 0)
			(size 0.3048 0.381)
			(layers "B.Cu" "B.Mask" "B.Paste")
			(net "P1V8_VDDA_PEX3")
		)
		(pad "2" smd rect
			(at -0.2667 0)
			(size 0.3048 0.381)
			(layers "B.Cu" "B.Mask" "B.Paste")
			(net "GND")
		)
	)
)
